(kicad_pcb
	(version 20260206)
	(generator "pcbnew")
	(generator_version "10.0")
	(general
		(thickness 1.6)
		(legacy_teardrops no)
	)
	(paper "A4")
	(title_block
		(title "04192023_DAF0TMB3IC0_F0TG_MB_C_brd_V02_OCP.brd")
		(comment 1 "Grand Teton / footprints 5838-5843 of 8354")
	)
	(layers
		(0 "F.Cu" signal "TOP")
		(4 "In1.Cu" signal "GND")
		(6 "In2.Cu" signal "IN1")
		(8 "In3.Cu" signal "GND1")
		(10 "In4.Cu" signal "IN2")
		(12 "In5.Cu" signal "GND2")
		(14 "In6.Cu" signal "IN3")
		(16 "In7.Cu" signal "GND3")
		(18 "In8.Cu" signal "VCC")
		(20 "In9.Cu" signal "VCC1")
		(22 "In10.Cu" signal "GND4")
		(24 "In11.Cu" signal "IN4")
		(26 "In12.Cu" signal "GND5")
		(28 "In13.Cu" signal "IN5")
		(30 "In14.Cu" signal "GND6")
		(32 "In15.Cu" signal "IN6")
		(34 "In16.Cu" signal "GND7")
		(2 "B.Cu" signal "BOTTOM")
		(9 "F.Adhes" user "F.Adhesive")
		(11 "B.Adhes" user "B.Adhesive")
		(13 "F.Paste" user "Package Geometry/Pastemask Top")
		(15 "B.Paste" user "Package Geometry/Pastemask Bottom")
		(5 "F.SilkS" user "Ref Des/Silkscreen Top")
		(7 "B.SilkS" user "Ref Des/Silkscreen Bottom")
		(1 "F.Mask" user "Board Geometry/Soldermask Top")
		(3 "B.Mask" user "Board Geometry/Soldermask Bottom")
		(17 "Dwgs.User" user "User.Drawings")
		(19 "Cmts.User" user "User.Comments")
		(21 "Eco1.User" user "User.Eco1")
		(23 "Eco2.User" user "User.Eco2")
		(25 "Edge.Cuts" user "Board Geometry/Outline")
		(27 "Margin" user)
		(31 "F.CrtYd" user "Package Geometry/Place Bound Top")
		(29 "B.CrtYd" user "Package Geometry/Place Bound Bottom")
		(35 "F.Fab" user "Ref Des/Assembly Top")
		(33 "B.Fab" user "Ref Des/Assembly Bottom")
	)
	(footprint ""
		(layer "B.Cu")
		(at 175.316642 -194.8942 180)
		(property "Reference" "R1587"
			(at 0 0 0)
			(layer "B.SilkS")
			(hide yes)
			(effects
				(font
					(size 1.27 1.27)
				)
				(justify mirror)
			)
		)
		(property "Value" ""
			(at 0 0 0)
			(layer "B.Fab")
			(effects
				(font
					(size 1.27 1.27)
				)
				(justify mirror)
			)
		)
		(duplicate_pad_numbers_are_jumpers no)
		(fp_line
			(start 0.7874 0.4064)
			(end 0.7874 -0.4064)
			(stroke
				(width 0.1524)
				(type default)
			)
			(layer "B.SilkS")
		)
		(fp_line
			(start 0.7874 -0.4064)
			(end -0.7874 -0.4064)
			(stroke
				(width 0.1524)
				(type default)
			)
			(layer "B.SilkS")
		)
		(fp_line
			(start -0.7874 0.4064)
			(end 0.7874 0.4064)
			(stroke
				(width 0.1524)
				(type default)
			)
			(layer "B.SilkS")
		)
		(fp_line
			(start -0.7874 -0.4064)
			(end -0.7874 0.4064)
			(stroke
				(width 0.1524)
				(type default)
			)
			(layer "B.SilkS")
		)
		(fp_line
			(start 0.67945 0.3048)
			(end 0.67945 -0.305054)
			(stroke
				(width 0.1)
				(type default)
			)
			(layer "B.Fab")
		)
		(fp_line
			(start 0.67945 -0.305054)
			(end 0.12065 -0.305054)
			(stroke
				(width 0.1)
				(type default)
			)
			(layer "B.Fab")
		)
		(fp_line
			(start 0.12065 0.3048)
			(end 0.67945 0.3048)
			(stroke
				(width 0.1)
				(type default)
			)
			(layer "B.Fab")
		)
		(fp_line
			(start 0.12065 0.2794)
			(end 0.12065 0.3048)
			(stroke
				(width 0.1)
				(type default)
			)
			(layer "B.Fab")
		)
		(fp_line
			(start 0.12065 -0.2794)
			(end -0.12065 -0.2794)
			(stroke
				(width 0.1)
				(type default)
			)
			(layer "B.Fab")
		)
		(fp_line
			(start 0.12065 -0.305054)
			(end 0.12065 -0.2794)
			(stroke
				(width 0.1)
				(type default)
			)
			(layer "B.Fab")
		)
		(fp_line
			(start -0.120396 0.3048)
			(end -0.120396 0.2794)
			(stroke
				(width 0.1)
				(type default)
			)
			(layer "B.Fab")
		)
		(fp_line
			(start -0.120396 0.2794)
			(end 0.12065 0.2794)
			(stroke
				(width 0.1)
				(type default)
			)
			(layer "B.Fab")
		)
		(fp_line
			(start -0.12065 -0.2794)
			(end -0.12065 -0.3048)
			(stroke
				(width 0.1)
				(type default)
			)
			(layer "B.Fab")
		)
		(fp_line
			(start -0.12065 -0.3048)
			(end -0.67945 -0.3048)
			(stroke
				(width 0.1)
				(type default)
			)
			(layer "B.Fab")
		)
		(fp_line
			(start -0.67945 0.3048)
			(end -0.120396 0.3048)
			(stroke
				(width 0.1)
				(type default)
			)
			(layer "B.Fab")
		)
		(fp_line
			(start -0.67945 -0.3048)
			(end -0.67945 0.3048)
			(stroke
				(width 0.1)
				(type default)
			)
			(layer "B.Fab")
		)
		(pad "1" smd circle
			(at 0.40005 0)
			(size 0 0)
			(layers "B.Cu" "B.Mask" "B.Paste")
			(net "I3C_SPD_DDRGL_CPU1_SCL")
		)
		(pad "2" smd circle
			(at -0.40005 0)
			(size 0 0)
			(layers "B.Cu" "B.Mask" "B.Paste")
			(net "I3C_SPD_DDRH_CPU1_SCL")
		)
	)
	(footprint ""
		(layer "B.Cu")
		(at 372.937278 -146.552158 180)
		(property "Reference" "R8304"
			(at 0 0 0)
			(layer "B.SilkS")
			(hide yes)
			(effects
				(font
					(size 1.27 1.27)
				)
				(justify mirror)
			)
		)
		(property "Value" ""
			(at 0 0 0)
			(layer "B.Fab")
			(effects
				(font
					(size 1.27 1.27)
				)
				(justify mirror)
			)
		)
		(duplicate_pad_numbers_are_jumpers no)
		(fp_line
			(start 0.7874 0.4064)
			(end 0.7874 -0.4064)
			(stroke
				(width 0.1524)
				(type default)
			)
			(layer "B.SilkS")
		)
		(fp_line
			(start 0.7874 -0.4064)
			(end -0.7874 -0.4064)
			(stroke
				(width 0.1524)
				(type default)
			)
			(layer "B.SilkS")
		)
		(fp_line
			(start -0.7874 0.4064)
			(end 0.7874 0.4064)
			(stroke
				(width 0.1524)
				(type default)
			)
			(layer "B.SilkS")
		)
		(fp_line
			(start -0.7874 -0.4064)
			(end -0.7874 0.4064)
			(stroke
				(width 0.1524)
				(type default)
			)
			(layer "B.SilkS")
		)
		(fp_line
			(start 0.67945 0.3048)
			(end 0.67945 -0.305054)
			(stroke
				(width 0.1)
				(type default)
			)
			(layer "B.Fab")
		)
		(fp_line
			(start 0.67945 -0.305054)
			(end 0.12065 -0.305054)
			(stroke
				(width 0.1)
				(type default)
			)
			(layer "B.Fab")
		)
		(fp_line
			(start 0.12065 0.3048)
			(end 0.67945 0.3048)
			(stroke
				(width 0.1)
				(type default)
			)
			(layer "B.Fab")
		)
		(fp_line
			(start 0.12065 0.2794)
			(end 0.12065 0.3048)
			(stroke
				(width 0.1)
				(type default)
			)
			(layer "B.Fab")
		)
		(fp_line
			(start 0.12065 -0.2794)
			(end -0.12065 -0.2794)
			(stroke
				(width 0.1)
				(type default)
			)
			(layer "B.Fab")
		)
		(fp_line
			(start 0.12065 -0.305054)
			(end 0.12065 -0.2794)
			(stroke
				(width 0.1)
				(type default)
			)
			(layer "B.Fab")
		)
		(fp_line
			(start -0.120396 0.3048)
			(end -0.120396 0.2794)
			(stroke
				(width 0.1)
				(type default)
			)
			(layer "B.Fab")
		)
		(fp_line
			(start -0.120396 0.2794)
			(end 0.12065 0.2794)
			(stroke
				(width 0.1)
				(type default)
			)
			(layer "B.Fab")
		)
		(fp_line
			(start -0.12065 -0.2794)
			(end -0.12065 -0.3048)
			(stroke
				(width 0.1)
				(type default)
			)
			(layer "B.Fab")
		)
		(fp_line
			(start -0.12065 -0.3048)
			(end -0.67945 -0.3048)
			(stroke
				(width 0.1)
				(type default)
			)
			(layer "B.Fab")
		)
		(fp_line
			(start -0.67945 0.3048)
			(end -0.120396 0.3048)
			(stroke
				(width 0.1)
				(type default)
			)
			(layer "B.Fab")
		)
		(fp_line
			(start -0.67945 -0.3048)
			(end -0.67945 0.3048)
			(stroke
				(width 0.1)
				(type default)
			)
			(layer "B.Fab")
		)
		(pad "1" smd circle
			(at 0.40005 0)
			(size 0 0)
			(layers "B.Cu" "B.Mask" "B.Paste")
			(net "SVID_PVDDCR_CPU0_P0_SVTO")
		)
		(pad "2" smd circle
			(at -0.40005 0)
			(size 0 0)
			(layers "B.Cu" "B.Mask" "B.Paste")
			(net "SVID_PVDDCR_CPU0_P0_SVTO_R")
		)
	)
	(footprint ""
		(layer "B.Cu")
		(at 346.987876 -66.708782 90)
		(property "Reference" "R3097"
			(at 0 0 90)
			(layer "B.SilkS")
			(hide yes)
			(effects
				(font
					(size 1.27 1.27)
				)
				(justify mirror)
			)
		)
		(property "Value" ""
			(at 0 0 90)
			(layer "B.Fab")
			(effects
				(font
					(size 1.27 1.27)
				)
				(justify mirror)
			)
		)
		(duplicate_pad_numbers_are_jumpers no)
		(fp_line
			(start 0.7874 -0.4064)
			(end -0.7874 -0.4064)
			(stroke
				(width 0.1524)
				(type default)
			)
			(layer "B.SilkS")
		)
		(fp_line
			(start -0.7874 -0.4064)
			(end -0.7874 0.4064)
			(stroke
				(width 0.1524)
				(type default)
			)
			(layer "B.SilkS")
		)
		(fp_line
			(start 0.7874 0.4064)
			(end 0.7874 -0.4064)
			(stroke
				(width 0.1524)
				(type default)
			)
			(layer "B.SilkS")
		)
		(fp_line
			(start -0.7874 0.4064)
			(end 0.7874 0.4064)
			(stroke
				(width 0.1524)
				(type default)
			)
			(layer "B.SilkS")
		)
		(fp_line
			(start 0.67945 -0.305054)
			(end 0.12065 -0.305054)
			(stroke
				(width 0.1)
				(type default)
			)
			(layer "B.Fab")
		)
		(fp_line
			(start 0.12065 -0.305054)
			(end 0.12065 -0.2794)
			(stroke
				(width 0.1)
				(type default)
			)
			(layer "B.Fab")
		)
		(fp_line
			(start -0.12065 -0.3048)
			(end -0.67945 -0.3048)
			(stroke
				(width 0.1)
				(type default)
			)
			(layer "B.Fab")
		)
		(fp_line
			(start -0.67945 -0.3048)
			(end -0.67945 0.3048)
			(stroke
				(width 0.1)
				(type default)
			)
			(layer "B.Fab")
		)
		(fp_line
			(start 0.12065 -0.2794)
			(end -0.12065 -0.2794)
			(stroke
				(width 0.1)
				(type default)
			)
			(layer "B.Fab")
		)
		(fp_line
			(start -0.12065 -0.2794)
			(end -0.12065 -0.3048)
			(stroke
				(width 0.1)
				(type default)
			)
			(layer "B.Fab")
		)
		(fp_line
			(start 0.12065 0.2794)
			(end 0.12065 0.3048)
			(stroke
				(width 0.1)
				(type default)
			)
			(layer "B.Fab")
		)
		(fp_line
			(start -0.120396 0.2794)
			(end 0.12065 0.2794)
			(stroke
				(width 0.1)
				(type default)
			)
			(layer "B.Fab")
		)
		(fp_line
			(start 0.67945 0.3048)
			(end 0.67945 -0.305054)
			(stroke
				(width 0.1)
				(type default)
			)
			(layer "B.Fab")
		)
		(fp_line
			(start 0.12065 0.3048)
			(end 0.67945 0.3048)
			(stroke
				(width 0.1)
				(type default)
			)
			(layer "B.Fab")
		)
		(fp_line
			(start -0.120396 0.3048)
			(end -0.120396 0.2794)
			(stroke
				(width 0.1)
				(type default)
			)
			(layer "B.Fab")
		)
		(fp_line
			(start -0.67945 0.3048)
			(end -0.120396 0.3048)
			(stroke
				(width 0.1)
				(type default)
			)
			(layer "B.Fab")
		)
		(pad "1" smd circle
			(at 0.40005 0 270)
			(size 0 0)
			(layers "B.Cu" "B.Mask" "B.Paste")
			(net "LED_PWRGD_PVDD18_S5_P1_R")
		)
		(pad "2" smd circle
			(at -0.40005 0 270)
			(size 0 0)
			(layers "B.Cu" "B.Mask" "B.Paste")
			(net "P3V3_AUX")
		)
	)
	(footprint ""
		(layer "B.Cu")
		(at 301.48657 -350.65589 -90)
		(property "Reference" "PC154_1"
			(at 0 0 90)
			(layer "B.SilkS")
			(hide yes)
			(effects
				(font
					(size 1.27 1.27)
				)
				(justify mirror)
			)
		)
		(property "Value" ""
			(at 0 0 90)
			(layer "B.Fab")
			(effects
				(font
					(size 1.27 1.27)
				)
				(justify mirror)
			)
		)
		(duplicate_pad_numbers_are_jumpers no)
		(fp_line
			(start -1.524 0.762)
			(end 1.524 0.762)
			(stroke
				(width 0.1524)
				(type default)
			)
			(layer "B.SilkS")
		)
		(fp_line
			(start 1.524 0.762)
			(end 1.524 -0.762)
			(stroke
				(width 0.1524)
				(type default)
			)
			(layer "B.SilkS")
		)
		(fp_line
			(start -1.524 -0.762)
			(end -1.524 0.762)
			(stroke
				(width 0.1524)
				(type default)
			)
			(layer "B.SilkS")
		)
		(fp_line
			(start 1.524 -0.762)
			(end -1.524 -0.762)
			(stroke
				(width 0.1524)
				(type default)
			)
			(layer "B.SilkS")
		)
		(fp_line
			(start -1.1049 0.724916)
			(end -1.1049 -0.724916)
			(stroke
				(width 0.1)
				(type default)
			)
			(layer "B.Fab")
		)
		(fp_line
			(start 1.1049 0.724916)
			(end -1.1049 0.724916)
			(stroke
				(width 0.1)
				(type default)
			)
			(layer "B.Fab")
		)
		(fp_line
			(start -1.1049 -0.724916)
			(end 1.1049 -0.724916)
			(stroke
				(width 0.1)
				(type default)
			)
			(layer "B.Fab")
		)
		(fp_line
			(start 1.1049 -0.724916)
			(end 1.1049 0.724916)
			(stroke
				(width 0.1)
				(type default)
			)
			(layer "B.Fab")
		)
		(pad "1" smd rect
			(at 0.889 0 270)
			(size 1.016 1.27)
			(layers "B.Cu" "B.Mask" "B.Paste")
			(net "SW_P12V_AUX_PVDDIO_P0_FLT")
		)
		(pad "2" smd rect
			(at -0.889 0 270)
			(size 1.016 1.27)
			(layers "B.Cu" "B.Mask" "B.Paste")
			(net "GND")
		)
	)
	(footprint ""
		(layer "B.Cu")
		(at 48.555148 -193.996564)
		(property "Reference" "R104"
			(at 0 0 0)
			(layer "B.SilkS")
			(hide yes)
			(effects
				(font
					(size 1.27 1.27)
				)
				(justify mirror)
			)
		)
		(property "Value" ""
			(at 0 0 0)
			(layer "B.Fab")
			(effects
				(font
					(size 1.27 1.27)
				)
				(justify mirror)
			)
		)
		(duplicate_pad_numbers_are_jumpers no)
		(fp_line
			(start -0.7874 -0.4064)
			(end -0.7874 0.4064)
			(stroke
				(width 0.1524)
				(type default)
			)
			(layer "B.SilkS")
		)
		(fp_line
			(start -0.7874 0.4064)
			(end 0.7874 0.4064)
			(stroke
				(width 0.1524)
				(type default)
			)
			(layer "B.SilkS")
		)
		(fp_line
			(start 0.7874 -0.4064)
			(end -0.7874 -0.4064)
			(stroke
				(width 0.1524)
				(type default)
			)
			(layer "B.SilkS")
		)
		(fp_line
			(start 0.7874 0.4064)
			(end 0.7874 -0.4064)
			(stroke
				(width 0.1524)
				(type default)
			)
			(layer "B.SilkS")
		)
		(fp_line
			(start -0.67945 -0.3048)
			(end -0.67945 0.3048)
			(stroke
				(width 0.1)
				(type default)
			)
			(layer "B.Fab")
		)
		(fp_line
			(start -0.67945 0.3048)
			(end -0.120396 0.3048)
			(stroke
				(width 0.1)
				(type default)
			)
			(layer "B.Fab")
		)
		(fp_line
			(start -0.12065 -0.3048)
			(end -0.67945 -0.3048)
			(stroke
				(width 0.1)
				(type default)
			)
			(layer "B.Fab")
		)
		(fp_line
			(start -0.12065 -0.2794)
			(end -0.12065 -0.3048)
			(stroke
				(width 0.1)
				(type default)
			)
			(layer "B.Fab")
		)
		(fp_line
			(start -0.120396 0.2794)
			(end 0.12065 0.2794)
			(stroke
				(width 0.1)
				(type default)
			)
			(layer "B.Fab")
		)
		(fp_line
			(start -0.120396 0.3048)
			(end -0.120396 0.2794)
			(stroke
				(width 0.1)
				(type default)
			)
			(layer "B.Fab")
		)
		(fp_line
			(start 0.12065 -0.305054)
			(end 0.12065 -0.2794)
			(stroke
				(width 0.1)
				(type default)
			)
			(layer "B.Fab")
		)
		(fp_line
			(start 0.12065 -0.2794)
			(end -0.12065 -0.2794)
			(stroke
				(width 0.1)
				(type default)
			)
			(layer "B.Fab")
		)
		(fp_line
			(start 0.12065 0.2794)
			(end 0.12065 0.3048)
			(stroke
				(width 0.1)
				(type default)
			)
			(layer "B.Fab")
		)
		(fp_line
			(start 0.12065 0.3048)
			(end 0.67945 0.3048)
			(stroke
				(width 0.1)
				(type default)
			)
			(layer "B.Fab")
		)
		(fp_line
			(start 0.67945 -0.305054)
			(end 0.12065 -0.305054)
			(stroke
				(width 0.1)
				(type default)
			)
			(layer "B.Fab")
		)
		(fp_line
			(start 0.67945 0.3048)
			(end 0.67945 -0.305054)
			(stroke
				(width 0.1)
				(type default)
			)
			(layer "B.Fab")
		)
		(pad "1" smd circle
			(at 0.40005 0 180)
			(size 0 0)
			(layers "B.Cu" "B.Mask" "B.Paste")
			(net "P3V3")
		)
		(pad "2" smd circle
			(at -0.40005 0 180)
			(size 0 0)
			(layers "B.Cu" "B.Mask" "B.Paste")
			(net "PWRGD_CHB_CPU1_DIMM")
		)
	)
	(footprint ""
		(layer "B.Cu")
		(at 372.937278 -144.520158 180)
		(property "Reference" "PR8006"
			(at 0 0 0)
			(layer "B.SilkS")
			(hide yes)
			(effects
				(font
					(size 1.27 1.27)
				)
				(justify mirror)
			)
		)
		(property "Value" ""
			(at 0 0 0)
			(layer "B.Fab")
			(effects
				(font
					(size 1.27 1.27)
				)
				(justify mirror)
			)
		)
		(duplicate_pad_numbers_are_jumpers no)
		(fp_line
			(start 0.7874 0.4064)
			(end 0.7874 -0.4064)
			(stroke
				(width 0.1524)
				(type default)
			)
			(layer "B.SilkS")
		)
		(fp_line
			(start 0.7874 -0.4064)
			(end -0.7874 -0.4064)
			(stroke
				(width 0.1524)
				(type default)
			)
			(layer "B.SilkS")
		)
		(fp_line
			(start -0.7874 0.4064)
			(end 0.7874 0.4064)
			(stroke
				(width 0.1524)
				(type default)
			)
			(layer "B.SilkS")
		)
		(fp_line
			(start -0.7874 -0.4064)
			(end -0.7874 0.4064)
			(stroke
				(width 0.1524)
				(type default)
			)
			(layer "B.SilkS")
		)
		(fp_line
			(start 0.67945 0.3048)
			(end 0.67945 -0.305054)
			(stroke
				(width 0.1)
				(type default)
			)
			(layer "B.Fab")
		)
		(fp_line
			(start 0.67945 -0.305054)
			(end 0.12065 -0.305054)
			(stroke
				(width 0.1)
				(type default)
			)
			(layer "B.Fab")
		)
		(fp_line
			(start 0.12065 0.3048)
			(end 0.67945 0.3048)
			(stroke
				(width 0.1)
				(type default)
			)
			(layer "B.Fab")
		)
		(fp_line
			(start 0.12065 0.2794)
			(end 0.12065 0.3048)
			(stroke
				(width 0.1)
				(type default)
			)
			(layer "B.Fab")
		)
		(fp_line
			(start 0.12065 -0.2794)
			(end -0.12065 -0.2794)
			(stroke
				(width 0.1)
				(type default)
			)
			(layer "B.Fab")
		)
		(fp_line
			(start 0.12065 -0.305054)
			(end 0.12065 -0.2794)
			(stroke
				(width 0.1)
				(type default)
			)
			(layer "B.Fab")
		)
		(fp_line
			(start -0.120396 0.3048)
			(end -0.120396 0.2794)
			(stroke
				(width 0.1)
				(type default)
			)
			(layer "B.Fab")
		)
		(fp_line
			(start -0.120396 0.2794)
			(end 0.12065 0.2794)
			(stroke
				(width 0.1)
				(type default)
			)
			(layer "B.Fab")
		)
		(fp_line
			(start -0.12065 -0.2794)
			(end -0.12065 -0.3048)
			(stroke
				(width 0.1)
				(type default)
			)
			(layer "B.Fab")
		)
		(fp_line
			(start -0.12065 -0.3048)
			(end -0.67945 -0.3048)
			(stroke
				(width 0.1)
				(type default)
			)
			(layer "B.Fab")
		)
		(fp_line
			(start -0.67945 0.3048)
			(end -0.120396 0.3048)
			(stroke
				(width 0.1)
				(type default)
			)
			(layer "B.Fab")
		)
		(fp_line
			(start -0.67945 -0.3048)
			(end -0.67945 0.3048)
			(stroke
				(width 0.1)
				(type default)
			)
			(layer "B.Fab")
		)
		(pad "1" smd circle
			(at 0.40005 0)
			(size 0 0)
			(layers "B.Cu" "B.Mask" "B.Paste")
			(net "SVID_PVDDCR_CPU0_P0_SVD_R")
		)
		(pad "2" smd circle
			(at -0.40005 0)
			(size 0 0)
			(layers "B.Cu" "B.Mask" "B.Paste")
			(net "SVID_PVDDCR_CPU0_P0_SVD_R1")
		)
	)
)
